(kicad_pcb
	(version 20260206)
	(generator "pcbnew")
	(generator_version "10.0")
	(general
		(thickness 1.6)
		(legacy_teardrops no)
	)
	(paper "A4")
	(title_block
		(title "peb — Lightning_PEB_BRD.brd")
		(comment 1 "Lightning (Wiwynn / Facebook NVMe JBOF) / footprints 2013-2021 of 2563")
	)
	(layers
		(0 "F.Cu" signal "TOP")
		(4 "In1.Cu" signal "L2GND")
		(6 "In2.Cu" signal "L3")
		(8 "In3.Cu" signal "L4VCC")
		(10 "In4.Cu" signal "L5VCC")
		(12 "In5.Cu" signal "L6")
		(14 "In6.Cu" signal "L7GND")
		(2 "B.Cu" signal "BOTTOM")
		(9 "F.Adhes" user "F.Adhesive")
		(11 "B.Adhes" user "B.Adhesive")
		(13 "F.Paste" user "Package Geometry/Pastemask Top")
		(15 "B.Paste" user "Package Geometry/Pastemask Bottom")
		(5 "F.SilkS" user "Ref Des/Silkscreen Top")
		(7 "B.SilkS" user "Ref Des/Silkscreen Bottom")
		(1 "F.Mask" user "Board Geometry/Soldermask Top")
		(3 "B.Mask" user "Board Geometry/Soldermask Bottom")
		(17 "Dwgs.User" user "User.Drawings")
		(19 "Cmts.User" user "User.Comments")
		(21 "Eco1.User" user "User.Eco1")
		(23 "Eco2.User" user "User.Eco2")
		(25 "Edge.Cuts" user "Board Geometry/Outline")
		(27 "Margin" user)
		(31 "F.CrtYd" user "Package Geometry/Place Bound Top")
		(29 "B.CrtYd" user "Package Geometry/Place Bound Bottom")
		(35 "F.Fab" user "Ref Des/Assembly Top")
		(33 "B.Fab" user "Ref Des/Assembly Bottom")
	)
	(footprint ""
		(layer "B.Cu")
		(at 332.613 -68.9356 90)
		(property "Reference" "PR21"
			(at 0 0 90)
			(layer "B.SilkS")
			(hide yes)
			(effects
				(font
					(size 1.27 1.27)
				)
				(justify mirror)
			)
		)
		(property "Value" "0R3J-0-U-GP"
			(at 0.0254 -2.5146 90)
			(unlocked yes)
			(layer "B.Fab")
			(hide yes)
			(effects
				(font
					(size 1.016 1.016)
					(thickness 0.1524)
				)
				(justify mirror)
			)
		)
		(property "Device Type" "R603H22"
			(at 0.0254 -4.0386 90)
			(unlocked yes)
			(layer "B.Fab")
			(hide yes)
			(effects
				(font
					(size 1.016 1.016)
					(thickness 0.1524)
				)
				(justify mirror)
			)
		)
		(duplicate_pad_numbers_are_jumpers no)
		(fp_line
			(start 0.4826 0)
			(end 0.2032 0)
			(stroke
				(width 0.2032)
				(type default)
			)
			(layer "B.SilkS")
		)
		(fp_line
			(start -0.2032 0)
			(end -0.4826 0)
			(stroke
				(width 0.2032)
				(type default)
			)
			(layer "B.SilkS")
		)
		(fp_rect
			(start 0.5842 1.3335)
			(end -0.5842 -1.3335)
			(stroke
				(width 0)
				(type default)
			)
			(fill no)
			(layer "B.CrtYd")
		)
		(fp_rect
			(start 0.5842 1.3335)
			(end -0.5842 -1.3335)
			(stroke
				(width 0)
				(type default)
			)
			(fill no)
			(layer "B.Fab")
		)
		(pad "1" smd custom
			(at 0 -0.762 270)
			(size 0.2159 0.2159)
			(layers "B.Cu" "B.Mask" "B.Paste")
			(net "P0V9_E_LX")
			(options
				(clearance outline)
				(anchor circle)
			)
			(primitives
				(gr_poly
					(pts
						(arc
							(start -0.3302 0.4318)
							(mid -0.402042 0.402042)
							(end -0.4318 0.3302)
						)
						(arc
							(start -0.4318 -0.3302)
							(mid -0.402042 -0.402042)
							(end -0.3302 -0.4318)
						)
						(arc
							(start 0.3302 -0.4318)
							(mid 0.402042 -0.402042)
							(end 0.4318 -0.3302)
						)
						(arc
							(start 0.4318 0.3302)
							(mid 0.402042 0.402042)
							(end 0.3302 0.4318)
						)
					)
					(width 0)
					(fill yes)
				)
			)
		)
		(pad "2" smd custom
			(at 0 0.762 270)
			(size 0.2159 0.2159)
			(layers "B.Cu" "B.Mask" "B.Paste")
			(net "P0V9_E_VBST_RC")
			(options
				(clearance outline)
				(anchor circle)
			)
			(primitives
				(gr_poly
					(pts
						(arc
							(start -0.3302 0.4318)
							(mid -0.402042 0.402042)
							(end -0.4318 0.3302)
						)
						(arc
							(start -0.4318 -0.3302)
							(mid -0.402042 -0.402042)
							(end -0.3302 -0.4318)
						)
						(arc
							(start 0.3302 -0.4318)
							(mid 0.402042 -0.402042)
							(end 0.4318 -0.3302)
						)
						(arc
							(start 0.4318 0.3302)
							(mid 0.402042 0.402042)
							(end 0.3302 0.4318)
						)
					)
					(width 0)
					(fill yes)
				)
			)
		)
	)
	(footprint ""
		(layer "B.Cu")
		(at 147.946618 -33.53562)
		(property "Reference" "R2920"
			(at 0 0 0)
			(layer "B.SilkS")
			(hide yes)
			(effects
				(font
					(size 1.27 1.27)
				)
				(justify mirror)
			)
		)
		(property "Value" "0R2J-2-GP"
			(at -0.064008 -3.993896 0)
			(unlocked yes)
			(layer "B.Fab")
			(hide yes)
			(effects
				(font
					(size 1.016 1.016)
					(thickness 0.1524)
				)
				(justify mirror)
			)
		)
		(property "Device Type" "R402H16"
			(at -0.064008 -5.517896 0)
			(unlocked yes)
			(layer "B.Fab")
			(hide yes)
			(effects
				(font
					(size 1.016 1.016)
					(thickness 0.1524)
				)
				(justify mirror)
			)
		)
		(duplicate_pad_numbers_are_jumpers no)
		(fp_line
			(start -0.508 -0.9398)
			(end 0.508 -0.9398)
			(stroke
				(width 0.1524)
				(type default)
			)
			(layer "B.SilkS")
		)
		(fp_line
			(start 0.508 -0.9398)
			(end 0.508 0.9398)
			(stroke
				(width 0.1524)
				(type default)
			)
			(layer "B.SilkS")
		)
		(fp_rect
			(start 0.508 0.9398)
			(end -0.508 -0.9398)
			(stroke
				(width 0)
				(type default)
			)
			(fill no)
			(layer "B.CrtYd")
		)
		(fp_rect
			(start 0.508 0.9398)
			(end -0.508 -0.9398)
			(stroke
				(width 0)
				(type default)
			)
			(fill no)
			(layer "B.Fab")
		)
		(pad "1" smd custom
			(at 0 -0.4445 180)
			(size 0.1397 0.1397)
			(layers "B.Cu" "B.Mask" "B.Paste")
			(net "CBL_PRSNT_N_2")
			(options
				(clearance outline)
				(anchor circle)
			)
			(primitives
				(gr_poly
					(pts
						(arc
							(start -0.1778 0.2794)
							(mid -0.249642 0.249642)
							(end -0.2794 0.1778)
						)
						(arc
							(start -0.2794 -0.1778)
							(mid -0.249642 -0.249642)
							(end -0.1778 -0.2794)
						)
						(arc
							(start 0.1778 -0.2794)
							(mid 0.249642 -0.249642)
							(end 0.2794 -0.1778)
						)
						(arc
							(start 0.2794 0.1778)
							(mid 0.249642 0.249642)
							(end 0.1778 0.2794)
						)
					)
					(width 0)
					(fill yes)
				)
			)
		)
		(pad "2" smd custom
			(at 0 0.4445 180)
			(size 0.1397 0.1397)
			(layers "B.Cu" "B.Mask" "B.Paste")
			(net "8644_CBL_PRSNT_R_2")
			(options
				(clearance outline)
				(anchor circle)
			)
			(primitives
				(gr_poly
					(pts
						(arc
							(start -0.1778 0.2794)
							(mid -0.249642 0.249642)
							(end -0.2794 0.1778)
						)
						(arc
							(start -0.2794 -0.1778)
							(mid -0.249642 -0.249642)
							(end -0.1778 -0.2794)
						)
						(arc
							(start 0.1778 -0.2794)
							(mid 0.249642 -0.249642)
							(end 0.2794 -0.1778)
						)
						(arc
							(start 0.2794 0.1778)
							(mid 0.249642 0.249642)
							(end 0.1778 0.2794)
						)
					)
					(width 0)
					(fill yes)
				)
			)
		)
	)
	(footprint ""
		(layer "B.Cu")
		(at 230.604822 -60.1218)
		(property "Reference" "C543"
			(at 0 0 0)
			(layer "B.SilkS")
			(hide yes)
			(effects
				(font
					(size 1.27 1.27)
				)
				(justify mirror)
			)
		)
		(property "Value" "SCD1U16V1KX-1-GP"
			(at 2.8321 -1.7399 0)
			(unlocked yes)
			(layer "B.Fab")
			(hide yes)
			(effects
				(font
					(size 1.016 1.016)
					(thickness 0.1524)
				)
				(justify mirror)
			)
		)
		(property "Device Type" "C0201H13"
			(at 2.8321 -3.2639 0)
			(unlocked yes)
			(layer "B.Fab")
			(hide yes)
			(effects
				(font
					(size 1.016 1.016)
					(thickness 0.1524)
				)
				(justify mirror)
			)
		)
		(duplicate_pad_numbers_are_jumpers no)
		(fp_rect
			(start 0.2794 0.6477)
			(end -0.2794 -0.6477)
			(stroke
				(width 0)
				(type default)
			)
			(fill no)
			(layer "B.CrtYd")
		)
		(fp_rect
			(start 0.2794 0.6477)
			(end -0.2794 -0.6477)
			(stroke
				(width 0)
				(type default)
			)
			(fill no)
			(layer "B.Fab")
		)
		(pad "1" smd custom
			(at 0 -0.2794 180)
			(size 0.0762 0.0762)
			(layers "B.Cu" "B.Mask" "B.Paste")
			(net "DUT_AVD_PCIE")
			(options
				(clearance outline)
				(anchor circle)
			)
			(primitives
				(gr_poly
					(pts
						(arc
							(start 0.1524 0.127)
							(mid 0.137521 0.162921)
							(end 0.1016 0.1778)
						)
						(arc
							(start -0.1016 0.1778)
							(mid -0.137521 0.162921)
							(end -0.1524 0.127)
						)
						(arc
							(start -0.1524 -0.127)
							(mid -0.137521 -0.162921)
							(end -0.1016 -0.1778)
						)
						(arc
							(start 0.1016 -0.1778)
							(mid 0.137521 -0.162921)
							(end 0.1524 -0.127)
						)
					)
					(width 0)
					(fill yes)
				)
			)
		)
		(pad "2" smd custom
			(at 0 0.2794 180)
			(size 0.0762 0.0762)
			(layers "B.Cu" "B.Mask" "B.Paste")
			(net "GND")
			(options
				(clearance outline)
				(anchor circle)
			)
			(primitives
				(gr_poly
					(pts
						(arc
							(start 0.1524 0.127)
							(mid 0.137521 0.162921)
							(end 0.1016 0.1778)
						)
						(arc
							(start -0.1016 0.1778)
							(mid -0.137521 0.162921)
							(end -0.1524 0.127)
						)
						(arc
							(start -0.1524 -0.127)
							(mid -0.137521 -0.162921)
							(end -0.1016 -0.1778)
						)
						(arc
							(start 0.1016 -0.1778)
							(mid 0.137521 -0.162921)
							(end 0.1524 -0.127)
						)
					)
					(width 0)
					(fill yes)
				)
			)
		)
	)
	(footprint ""
		(layer "B.Cu")
		(at 252.603 -55.998872 -90)
		(property "Reference" "C579"
			(at 0 0 90)
			(layer "B.SilkS")
			(hide yes)
			(effects
				(font
					(size 1.27 1.27)
				)
				(justify mirror)
			)
		)
		(property "Value" "SCD1U16V1KX-1-GP"
			(at 2.8321 -1.7399 270)
			(unlocked yes)
			(layer "B.Fab")
			(hide yes)
			(effects
				(font
					(size 1.016 1.016)
					(thickness 0.1524)
				)
				(justify mirror)
			)
		)
		(property "Device Type" "C0201H13"
			(at 2.8321 -3.2639 270)
			(unlocked yes)
			(layer "B.Fab")
			(hide yes)
			(effects
				(font
					(size 1.016 1.016)
					(thickness 0.1524)
				)
				(justify mirror)
			)
		)
		(duplicate_pad_numbers_are_jumpers no)
		(fp_rect
			(start 0.2794 0.6477)
			(end -0.2794 -0.6477)
			(stroke
				(width 0)
				(type default)
			)
			(fill no)
			(layer "B.CrtYd")
		)
		(fp_rect
			(start 0.2794 0.6477)
			(end -0.2794 -0.6477)
			(stroke
				(width 0)
				(type default)
			)
			(fill no)
			(layer "B.Fab")
		)
		(pad "1" smd custom
			(at 0 -0.2794 90)
			(size 0.0762 0.0762)
			(layers "B.Cu" "B.Mask" "B.Paste")
			(net "DUT_AVD_PCIE")
			(options
				(clearance outline)
				(anchor circle)
			)
			(primitives
				(gr_poly
					(pts
						(arc
							(start 0.1524 0.127)
							(mid 0.137521 0.162921)
							(end 0.1016 0.1778)
						)
						(arc
							(start -0.1016 0.1778)
							(mid -0.137521 0.162921)
							(end -0.1524 0.127)
						)
						(arc
							(start -0.1524 -0.127)
							(mid -0.137521 -0.162921)
							(end -0.1016 -0.1778)
						)
						(arc
							(start 0.1016 -0.1778)
							(mid 0.137521 -0.162921)
							(end 0.1524 -0.127)
						)
					)
					(width 0)
					(fill yes)
				)
			)
		)
		(pad "2" smd custom
			(at 0 0.2794 90)
			(size 0.0762 0.0762)
			(layers "B.Cu" "B.Mask" "B.Paste")
			(net "GND")
			(options
				(clearance outline)
				(anchor circle)
			)
			(primitives
				(gr_poly
					(pts
						(arc
							(start 0.1524 0.127)
							(mid 0.137521 0.162921)
							(end 0.1016 0.1778)
						)
						(arc
							(start -0.1016 0.1778)
							(mid -0.137521 0.162921)
							(end -0.1524 0.127)
						)
						(arc
							(start -0.1524 -0.127)
							(mid -0.137521 -0.162921)
							(end -0.1016 -0.1778)
						)
						(arc
							(start 0.1016 -0.1778)
							(mid 0.137521 -0.162921)
							(end 0.1524 -0.127)
						)
					)
					(width 0)
					(fill yes)
				)
			)
		)
	)
	(footprint ""
		(layer "B.Cu")
		(at 249.428 -25.4 -90)
		(property "Reference" "TP287"
			(at 0 0 90)
			(layer "B.SilkS")
			(hide yes)
			(effects
				(font
					(size 1.27 1.27)
				)
				(justify mirror)
			)
		)
		(property "Value" "TPAD28-2-GP"
			(at 0.0127 -1.6637 270)
			(unlocked yes)
			(layer "B.Fab")
			(hide yes)
			(effects
				(font
					(size 1.016 1.016)
					(thickness 0.1524)
				)
				(justify mirror)
			)
		)
		(property "Device Type" "TPAD28"
			(at 0.0127 -3.1877 270)
			(unlocked yes)
			(layer "B.Fab")
			(hide yes)
			(effects
				(font
					(size 1.016 1.016)
					(thickness 0.1524)
				)
				(justify mirror)
			)
		)
		(duplicate_pad_numbers_are_jumpers no)
		(fp_poly
			(pts
				(arc
					(start 0 -0.3556)
					(mid 0 0.3556)
					(end 0 -0.3556)
				)
			)
			(stroke
				(width 0)
				(type default)
			)
			(fill no)
			(layer "B.CrtYd")
		)
		(fp_poly
			(pts
				(arc
					(start 0 -0.6096)
					(mid 0 0.6096)
					(end 0 -0.6096)
				)
			)
			(stroke
				(width 0)
				(type default)
			)
			(fill no)
			(layer "B.Fab")
		)
		(pad "1" smd circle
			(at 0 0 90)
			(size 0.7112 0.7112)
			(layers "B.Cu" "B.Mask" "B.Paste")
			(net "TWI_SDA5")
		)
	)
	(footprint ""
		(layer "B.Cu")
		(at 242.0366 -25.1206)
		(property "Reference" "TP211"
			(at 0 0 0)
			(layer "B.SilkS")
			(hide yes)
			(effects
				(font
					(size 1.27 1.27)
				)
				(justify mirror)
			)
		)
		(property "Value" "TPAD28-2-GP"
			(at 0.0127 -1.6637 0)
			(unlocked yes)
			(layer "B.Fab")
			(hide yes)
			(effects
				(font
					(size 1.016 1.016)
					(thickness 0.1524)
				)
				(justify mirror)
			)
		)
		(property "Device Type" "TPAD28"
			(at 0.0127 -3.1877 0)
			(unlocked yes)
			(layer "B.Fab")
			(hide yes)
			(effects
				(font
					(size 1.016 1.016)
					(thickness 0.1524)
				)
				(justify mirror)
			)
		)
		(duplicate_pad_numbers_are_jumpers no)
		(fp_poly
			(pts
				(arc
					(start 0.3556 0)
					(mid -0.3556 0)
					(end 0.3556 0)
				)
			)
			(stroke
				(width 0)
				(type default)
			)
			(fill no)
			(layer "B.CrtYd")
		)
		(fp_poly
			(pts
				(arc
					(start 0.6096 0)
					(mid -0.6096 0)
					(end 0.6096 0)
				)
			)
			(stroke
				(width 0)
				(type default)
			)
			(fill no)
			(layer "B.Fab")
		)
		(pad "1" smd circle
			(at 0 0 180)
			(size 0.7112 0.7112)
			(layers "B.Cu" "B.Mask" "B.Paste")
			(net "LBI_DATA_2")
		)
	)
	(footprint ""
		(layer "B.Cu")
		(at 312.039 -68.58 180)
		(property "Reference" "PC180"
			(at 0 0 0)
			(layer "B.SilkS")
			(hide yes)
			(effects
				(font
					(size 1.27 1.27)
				)
				(justify mirror)
			)
		)
		(property "Value" "SC22U6D3V5MX-5-GP"
			(at 0.0762 -6.1214 180)
			(unlocked yes)
			(layer "B.Fab")
			(hide yes)
			(effects
				(font
					(size 1.016 1.016)
					(thickness 0.1524)
				)
				(justify mirror)
			)
		)
		(property "Device Type" "C805H56"
			(at 0.0762 -8.1534 180)
			(unlocked yes)
			(layer "B.Fab")
			(hide yes)
			(effects
				(font
					(size 1.016 1.016)
					(thickness 0.1524)
				)
				(justify mirror)
			)
		)
		(duplicate_pad_numbers_are_jumpers no)
		(fp_line
			(start -0.635 0)
			(end 0.635 0)
			(stroke
				(width 0.508)
				(type default)
			)
			(layer "B.SilkS")
		)
		(fp_rect
			(start 0.9652 1.778)
			(end -0.9652 -1.778)
			(stroke
				(width 0)
				(type default)
			)
			(fill no)
			(layer "B.CrtYd")
		)
		(fp_poly
			(pts
				(xy 0.9652 -1.778) (xy -0.9652 -1.778) (xy -0.9652 1.778) (xy 0.9652 1.778)
			)
			(stroke
				(width 0)
				(type default)
			)
			(fill no)
			(layer "B.Fab")
		)
		(pad "1" smd rect
			(at 0 -0.9652)
			(size 1.397 1.143)
			(layers "B.Cu" "B.Mask" "B.Paste")
			(net "P0V9_E")
		)
		(pad "2" smd rect
			(at 0 0.9652)
			(size 1.397 1.143)
			(layers "B.Cu" "B.Mask" "B.Paste")
			(net "GND")
		)
	)
	(footprint ""
		(layer "B.Cu")
		(at 226.822 -20.447)
		(property "Reference" "R3704"
			(at 0 0 0)
			(layer "B.SilkS")
			(hide yes)
			(effects
				(font
					(size 1.27 1.27)
				)
				(justify mirror)
			)
		)
		(property "Value" "4K7R2F-GP"
			(at -0.064008 -3.993896 0)
			(unlocked yes)
			(layer "B.Fab")
			(hide yes)
			(effects
				(font
					(size 1.016 1.016)
					(thickness 0.1524)
				)
				(justify mirror)
			)
		)
		(property "Device Type" "R402H16"
			(at -0.064008 -5.517896 0)
			(unlocked yes)
			(layer "B.Fab")
			(hide yes)
			(effects
				(font
					(size 1.016 1.016)
					(thickness 0.1524)
				)
				(justify mirror)
			)
		)
		(duplicate_pad_numbers_are_jumpers no)
		(fp_line
			(start -0.508 -0.9398)
			(end 0.508 -0.9398)
			(stroke
				(width 0.1524)
				(type default)
			)
			(layer "B.SilkS")
		)
		(fp_line
			(start 0.508 -0.9398)
			(end 0.508 0.9398)
			(stroke
				(width 0.1524)
				(type default)
			)
			(layer "B.SilkS")
		)
		(fp_rect
			(start 0.508 0.9398)
			(end -0.508 -0.9398)
			(stroke
				(width 0)
				(type default)
			)
			(fill no)
			(layer "B.CrtYd")
		)
		(fp_rect
			(start 0.508 0.9398)
			(end -0.508 -0.9398)
			(stroke
				(width 0)
				(type default)
			)
			(fill no)
			(layer "B.Fab")
		)
		(pad "1" smd custom
			(at 0 -0.4445 180)
			(size 0.1397 0.1397)
			(layers "B.Cu" "B.Mask" "B.Paste")
			(net "HOST4_RST_N_LS")
			(options
				(clearance outline)
				(anchor circle)
			)
			(primitives
				(gr_poly
					(pts
						(arc
							(start -0.1778 0.2794)
							(mid -0.249642 0.249642)
							(end -0.2794 0.1778)
						)
						(arc
							(start -0.2794 -0.1778)
							(mid -0.249642 -0.249642)
							(end -0.1778 -0.2794)
						)
						(arc
							(start 0.1778 -0.2794)
							(mid 0.249642 -0.249642)
							(end 0.2794 -0.1778)
						)
						(arc
							(start 0.2794 0.1778)
							(mid 0.249642 0.249642)
							(end 0.1778 0.2794)
						)
					)
					(width 0)
					(fill yes)
				)
			)
		)
		(pad "2" smd custom
			(at 0 0.4445 180)
			(size 0.1397 0.1397)
			(layers "B.Cu" "B.Mask" "B.Paste")
			(net "DUT_VDDO")
			(options
				(clearance outline)
				(anchor circle)
			)
			(primitives
				(gr_poly
					(pts
						(arc
							(start -0.1778 0.2794)
							(mid -0.249642 0.249642)
							(end -0.2794 0.1778)
						)
						(arc
							(start -0.2794 -0.1778)
							(mid -0.249642 -0.249642)
							(end -0.1778 -0.2794)
						)
						(arc
							(start 0.1778 -0.2794)
							(mid 0.249642 -0.249642)
							(end 0.2794 -0.1778)
						)
						(arc
							(start 0.2794 0.1778)
							(mid 0.249642 0.249642)
							(end 0.1778 0.2794)
						)
					)
					(width 0)
					(fill yes)
				)
			)
		)
	)
	(footprint ""
		(layer "B.Cu")
		(at 238.252 -20.447)
		(property "Reference" "R797"
			(at 0 0 0)
			(layer "B.SilkS")
			(hide yes)
			(effects
				(font
					(size 1.27 1.27)
				)
				(justify mirror)
			)
		)
		(property "Value" "4K7R2F-GP"
			(at -0.064008 -3.993896 0)
			(unlocked yes)
			(layer "B.Fab")
			(hide yes)
			(effects
				(font
					(size 1.016 1.016)
					(thickness 0.1524)
				)
				(justify mirror)
			)
		)
		(property "Device Type" "R402H16"
			(at -0.064008 -5.517896 0)
			(unlocked yes)
			(layer "B.Fab")
			(hide yes)
			(effects
				(font
					(size 1.016 1.016)
					(thickness 0.1524)
				)
				(justify mirror)
			)
		)
		(duplicate_pad_numbers_are_jumpers no)
		(fp_line
			(start -0.508 -0.9398)
			(end 0.508 -0.9398)
			(stroke
				(width 0.1524)
				(type default)
			)
			(layer "B.SilkS")
		)
		(fp_line
			(start 0.508 -0.9398)
			(end 0.508 0.9398)
			(stroke
				(width 0.1524)
				(type default)
			)
			(layer "B.SilkS")
		)
		(fp_rect
			(start 0.508 0.9398)
			(end -0.508 -0.9398)
			(stroke
				(width 0)
				(type default)
			)
			(fill no)
			(layer "B.CrtYd")
		)
		(fp_rect
			(start 0.508 0.9398)
			(end -0.508 -0.9398)
			(stroke
				(width 0)
				(type default)
			)
			(fill no)
			(layer "B.Fab")
		)
		(pad "1" smd custom
			(at 0 -0.4445 180)
			(size 0.1397 0.1397)
			(layers "B.Cu" "B.Mask" "B.Paste")
			(net "BOOTSTRAP2")
			(options
				(clearance outline)
				(anchor circle)
			)
			(primitives
				(gr_poly
					(pts
						(arc
							(start -0.1778 0.2794)
							(mid -0.249642 0.249642)
							(end -0.2794 0.1778)
						)
						(arc
							(start -0.2794 -0.1778)
							(mid -0.249642 -0.249642)
							(end -0.1778 -0.2794)
						)
						(arc
							(start 0.1778 -0.2794)
							(mid 0.249642 -0.249642)
							(end 0.2794 -0.1778)
						)
						(arc
							(start 0.2794 0.1778)
							(mid 0.249642 0.249642)
							(end 0.1778 0.2794)
						)
					)
					(width 0)
					(fill yes)
				)
			)
		)
		(pad "2" smd custom
			(at 0 0.4445 180)
			(size 0.1397 0.1397)
			(layers "B.Cu" "B.Mask" "B.Paste")
			(net "DUT_VDDO")
			(options
				(clearance outline)
				(anchor circle)
			)
			(primitives
				(gr_poly
					(pts
						(arc
							(start -0.1778 0.2794)
							(mid -0.249642 0.249642)
							(end -0.2794 0.1778)
						)
						(arc
							(start -0.2794 -0.1778)
							(mid -0.249642 -0.249642)
							(end -0.1778 -0.2794)
						)
						(arc
							(start 0.1778 -0.2794)
							(mid 0.249642 -0.249642)
							(end 0.2794 -0.1778)
						)
						(arc
							(start 0.2794 0.1778)
							(mid 0.249642 0.249642)
							(end 0.1778 0.2794)
						)
					)
					(width 0)
					(fill yes)
				)
			)
		)
	)
)
